#ISCELL
  mstr_misc dns *
  *
#ISCELL
  mstr_symbols cad_note *
  *
#ISCELL
  mstr_symbols design_note *
  *
#ISCELL
  mstr_symbols intel_corp_bpage *
  *
#ISCELL
  mstr_standard offpage *
  page153_i101
#ISCELL
  mstr_standard offpage *
  page153_i102
#ISCELL
  mstr_standard offpage *
  page153_i103
#ISCELL
  mstr_standard offpage *
  page153_i105
#ISCELL
  mstr_standard offpage *
  page153_i107
#CELL
  mstr_discrete res *
  page153_i108
#CELL
  mstr_discrete res *
  page153_i109
#ISCELL
  mstr_standard offpage *
  page153_i110
#ISCELL
  mstr_standard offpage *
  page153_i111
#CELL
  dev_discrete cap_a *
  page153_i130
#CELL
  dev_discrete cap_a *
  page153_i131
#ISCELL
  mstr_symbols gnd *
  page153_i133
#CELL
  dev_discrete cap_a *
  page153_i136
#CELL
  dev_discrete cap_a *
  page153_i138
#ISCELL
  mstr_symbols gnd *
  page153_i139
#CELL
  mstr_discrete res *
  page153_i140
#ISCELL
  mstr_symbols p3v3_stby *
  page153_i141
#ISCELL
  mstr_standard offpage *
  page153_i144
#CELL
  mstr_memory w25q256 *
  page153_i146
#CELL
  mstr_discrete res *
  page153_i150
#ISCELL
  mstr_symbols p3v3_stby *
  page153_i151
#CELL
  mstr_discrete res *
  page153_i152
#ISCELL
  mstr_standard offpage *
  page153_i153
#CELL
  mstr_discrete res *
  page153_i155
#CELL
  mstr_discrete res *
  page153_i156
#CELL
  mstr_discrete res *
  page153_i157
#ISCELL
  mstr_standard offpage *
  page153_i158
#ISCELL
  mstr_standard offpage *
  page153_i159
#ISCELL
  mstr_standard offpage *
  page153_i161
#ISCELL
  mstr_standard offpage *
  page153_i162
#ISCELL
  mstr_standard offpage *
  page153_i163
#ISCELL
  mstr_standard offpage *
  page153_i164
#CELL
  mstr_discrete res *
  page153_i166
#CELL
  mstr_discrete res *
  page153_i167
#CELL
  mstr_discrete res *
  page153_i168
#ISCELL
  mstr_symbols p3v3_stby *
  page153_i169
#CELL
  mstr_discrete res *
  page153_i170
#ISCELL
  mstr_standard offpage *
  page153_i171
#ISCELL
  mstr_symbols gnd *
  page153_i172
#ISCELL
  mstr_standard offpage *
  page153_i173
#CELL
  mstr_discrete res *
  page153_i174
#ISCELL
  mstr_symbols p3v3_stby *
  page153_i175
#ISCELL
  mstr_symbols p3v3_stby *
  page153_i176
#ISCELL
  mstr_standard offpage *
  page153_i177
#CELL
  mstr_discrete res *
  page153_i178
#CELL
  mstr_discrete res *
  page153_i179
#ISCELL
  mstr_symbols gnd *
  page153_i180
#CELL
  mstr_discrete res *
  page153_i181
#ISCELL
  mstr_standard offpage *
  page153_i182
#ISCELL
  mstr_standard offpage *
  page153_i183
#CELL
  mstr_discrete res *
  page153_i184
#CELL
  w_hdl w25q256fvfig-gp *
  page153_i185
#ISCELL
  mstr_symbols gnd *
  page153_i186
#CELL
  mstr_discrete res *
  page153_i187
#ISCELL
  mstr_standard offpage *
  page153_i188
#CELL
  mstr_discrete res *
  page153_i90
#ISCELL
  mstr_symbols gnd *
  page153_i91
#CELL
  mstr_discrete res *
  page153_i94
#ISCELL
  mstr_symbols p3v3_stby *
  page153_i95
#CELL
  mstr_discrete res *
  page153_i98
